# S9S_MB_2U (Grand Teton) — schematic parts with pin connectivity, parts 5884–5894 of 6093; source: Cadence DE-HDL packaged netlist (pstxprt.dat, pstxnet.dat, pstchip.dat)

U4  EMMITSBURG_REV0P9  GFNOCPU04302300-QV2N-MM#99A1WT IC  pkg BGA749_22X23  page 179  (pins 605-749 of 749)
  K28  DMI_0_TXN  OUT  = DMI_CPU0_PCH_RX_DN<0>
  K31  DMI_3_TXP  OUT  = DMI_CPU0_PCH_RX_DP<3>
  K34  VSS_K34  POWER  = GND
  K37  DMI_6_SATA_17_PCIE3_17_TXN  OUT  = DMI_CPU0_PCH_RX_DN<6>
  K39  VSS_K39  POWER  = GND
  K41  SATA_12_PCIE3_12_GBE_1_RXN  IN  = TP_P3E_PCH_12_RX_DN
  K43  SATA_12_PCIE3_12_GBE_1_RXP  IN  = TP_P3E_PCH_12_RX_DP
  L2  GPPC_H_6  BI  = FM_PCH_EXTERNALCLKMODE
  L4  GPPC_H_19  BI  = FM_LT_KEY_DOWNGRADE_N
  L7  CPU_ERR2_N  IN  = H_CPU_ERR2_PCH_R_N
  L10  VSS_L10  POWER  = GND
  L13  RSVD_L13  TRI  = TP_PCH_RSVD<13>
  L16  VSS_L16  POWER  = GND
  L20  VSS_L20  POWER  = GND
  L23  VSS_L23  POWER  = GND
  L26  VSS_L26  POWER  = GND
  L29  VSS_L29  POWER  = GND
  L32  DMI_3_TXN  OUT  = DMI_CPU0_PCH_RX_DN<3>
  L36  VSS_L36  POWER  = GND
  L40  SATA_11_PCIE3_11_RXN  IN  = P3E_PCH_NVS_RX_DN<1>
  L42  SATA_11_PCIE3_11_RXP  IN  = P3E_PCH_NVS_RX_DP<1>
  M1  VSS_M1  POWER  = GND
  M3  VSS_M3  POWER  = GND
  M5  VSS_M5  POWER  = GND
  M8  PLTRST_CPU_N  OUT  = TP_PLTRST_N
  M11  VSS_M11  POWER  = GND
  M15  VSS_M15  POWER  = GND
  M18  VSS_M18  POWER  = GND
  M21  VSS_M21  POWER  = GND
  M24  VCCP_1P05_M24  POWER  = P1V05_PCH_AUX
  M28  VSS_M28  POWER  = GND
  M31  VSS_M31  POWER  = GND
  M34  VSS_M34  POWER  = GND
  M37  VSS_M37  POWER  = GND
  M39  VSS_M39  POWER  = GND
  M41  SATA_10_PCIE3_10_GBE_0_RXN  IN  = P3E_PCH_NVS_RX_DN<0>
  M43  SATA_10_PCIE3_10_GBE_0_RXP  IN  = P3E_PCH_NVS_RX_DP<0>
  N2  GPP_I_13_HDA_RST_N  BI  = PD_GPP_I_13
  N4  GPP_I_21  BI  = IRQ_TPM_SPI_N
  N7  GPP_M_0  BI  = FAB_REV_ID0
  N10  GPP_M_16  BI  = PD_GPP_M_16
  N13  RSVD_N13  TRI  = TP_PCH_RSVD<12>
  N16  VSS_N16  POWER  = GND
  N20  VCCP_1P8_N20  POWER  = P1V8_PCH_AUX
  N23  VCCP_1P05_N23  POWER  = P1V05_PCH_AUX
  N26  VCCP_1P05_N26  POWER  = P1V05_PCH_AUX
  N29  XCLK_BIASREF  BI  = PD_PCH_XCLK_BIASREF
  N32  VSS_N32  POWER  = GND
  N36  SATA_15_PCIE3_15_TXP  OUT  = TP_P3E_PCH_15_TX_DP
  N40  RSVD_N40  TRI  = NC_PCH_RSVD<10>
  N42  RSVD_N42  TRI  = NC_PCH_RSVD<11>
  P1  GPP_I_14_HDA_SYNC  BI  = PD_GPP_I_14
  P3  GPP_I_22  BI  = FM_PCH_DFXTESTMODE
  P5  VSS_P5  POWER  = GND
  P8  VSS_P8  POWER  = GND
  P11  VSS_P11  POWER  = GND
  P15  VCCP_1P05_P15  POWER  = P1V05_PCH_AUX
  P18  RSVD_P18  TRI  = TP_PCH_RSVD<6>
  P21  VCCP_3P3_P21  POWER  = P3V3_AUX
  P24  VSS_P24  POWER  = GND
  P28  VSS_P28  POWER  = GND
  P31  VSS_P31  POWER  = GND
  P34  SATA_15_PCIE3_15_TXN  OUT  = TP_P3E_PCH_15_TX_DN
  P37  VSS_P37  POWER  = GND
  P39  VSS_P39  POWER  = GND
  P41  VSS_P41  POWER  = GND
  P43  VSS_P43  POWER  = GND
  R2  GPP_I_15_HDA_SDO  BI  = PD_GPP_I_15
  R4  GPP_I_23  BI  = FM_PCH_XTALSEL
  R7  GPP_M_11  BI  = FM_PCH_BIOS_RCVR_MODE
  R10  GPP_M_6  BI  = FM_BOARD_SKU_ID3
  R13  VSS_R13  POWER  = GND
  R16  VSS_R16  POWER  = GND
  R20  VSS_R20  POWER  = GND
  R23  VCCP_1P05_FILTERED_R23  POWER  = P1V05_PCH_PLL_AUX
  R26  VCCP_1P05_FILTERED_R26  POWER  = P1V05_PCH_PLL_AUX
  R29  VCCP_1P05_FILTERED_R29  POWER  = P1V05_PCH_PLL_AUX
  R32  SATA_14_PCIE3_14_GBE_2_TXN  OUT  = TP_P3E_PCH_14_TX_DN
  R36  VSS_R36  POWER  = GND
  R40  SATA_9_PCIE3_9_USB3_9_RXN  IN  = USB3_PCH_RX_BUF_DN<4>
  R42  SATA_9_PCIE3_9_USB3_9_RXP  IN  = USB3_PCH_RX_BUF_DP<4>
  T8  GPP_M_15  BI  = PD_GPP_M_15
  T11  GPP_N_1  BI  = TP_PCH_GPP_N_1
  T15  VCCP_GPPD_1P8_3P3  POWER  = P3V3_AUX
  T31  VSS_T31  POWER  = GND
  T34  SATA_14_PCIE3_14_GBE_2_TXP  OUT  = TP_P3E_PCH_14_TX_DP
  T37  SATA_11_PCIE3_11_TXN  OUT  = P3E_PCH_NVS_TX_DN<1>
  U1  GPP_I_16_HDA_SDI_0  BI  = PD_GPP_I_16
  U3  GPP_I_12_HDA_BCLK  BI  = FM_PCH_BMC_RST_R_N
  U5  VSS_U5  POWER  = GND
  U7  GPP_M_12  BI  = TP_GPP_M_12
  U10  VSS_U10  POWER  = GND
  U13  VSS_U13  POWER  = GND
  U17  VCCP_1P8_U17  POWER  = P1V8_PCH_AUX
  U19  VCCP_1P8_U19  POWER  = P1V8_PCH_AUX
  U20  VCCP_1P8_U20  POWER  = P1V8_PCH_AUX
  U22  VCCP_1P8_U22  POWER  = P1V8_PCH_AUX
  U24  VCCP_1P8_U24  POWER  = P1V8_PCH_AUX
  U25  VSS_U25  POWER  = GND
  U27  VCCP_1P05_FILTERED_U27  POWER  = P1V05_PCH_PLL_AUX
  U29  VCCP_1P8_FILTERED_U29  POWER  = P1V8_PCH_PLL_AUX
  U32  SATA_13_PCIE3_13_TXN  OUT  = TP_P3E_PCH_13_TX_DN
  U36  SATA_12_PCIE3_12_GBE_1_TXP  OUT  = TP_P3E_PCH_12_TX_DP
  U39  VSS_U39  POWER  = GND
  U41  SATA_8_PCIE3_8_USB3_8_RXN  IN  = P3E_PCH_BMC_RX_DN
  U43  SATA_8_PCIE3_8_USB3_8_RXP  IN  = P3E_PCH_BMC_RX_DP
  V2  VSS_V2  POWER  = GND
  V4  GPP_I_17_HDA_SDI_1  BI  = PD_GPP_I_17
  V8  GPP_M_5  BI  = FM_BOARD_SKU_ID2
  V11  GPP_N_4  BI  = TP_PCH_GPP_N_4
  V15  VCCP_3P3_DSW_V15  POWER  = P3V3_AUX
  V31  VSS_V31  POWER  = GND
  V34  SATA_12_PCIE3_12_GBE_1_TXN  OUT  = TP_P3E_PCH_12_TX_DN
  V37  SATA_11_PCIE3_11_TXP  OUT  = P3E_PCH_NVS_TX_DP<1>
  V40  SATA_7_PCIE3_7_USB3_7_RXN  IN  = P3E_PCH_E1S_RX_DN<3>
  V42  SATA_7_PCIE3_7_USB3_7_RXP  IN  = P3E_PCH_E1S_RX_DP<3>
  W1  GPP_D_23  BI  = FM_PCH_BOOT_BIOS_STRAP
  W3  VSS_W3  POWER  = GND
  W5  VSS_W5  POWER  = GND
  W7  GPP_M_4  BI  = FM_BOARD_SKU_ID1
  W10  GPP_M_8  BI  = PD_GPP_M_8
  W13  GPP_M_17  BI  = PD_GPP_M_17
  W17  VCCP_1P05_W17  POWER  = P1V05_PCH_AUX
  W19  VCCP_1P05_W19  POWER  = P1V05_PCH_AUX
  W20  VCCP_1P05_W20  POWER  = P1V05_PCH_AUX
  W22  VCCP_1P05_W22  POWER  = P1V05_PCH_AUX
  W24  VCCP_1P05_W24  POWER  = P1V05_PCH_AUX
  W25  VSS_W25  POWER  = GND
  W27  VCCP_1P8_FILTERED_W27  POWER  = P1V8_PCH_PLL_AUX
  W29  VCCP_1P8_FILTERED_W29  POWER  = P1V8_PCH_PLL_AUX
  W32  SATA_13_PCIE3_13_TXP  OUT  = TP_P3E_PCH_13_TX_DP
  W36  SATA_10_PCIE3_10_GBE_0_TXN  OUT  = P3E_PCH_NVS_TX_DN<0>
  W39  VSS_W39  POWER  = GND
  W41  SATA_6_PCIE3_6_USB3_6_RXN  IN  = P3E_PCH_E1S_RX_DN<2>
  W43  SATA_6_PCIE3_6_USB3_6_RXP  IN  = P3E_PCH_E1S_RX_DP<2>
  Y2  GPP_D_17_THERMTRIP_N  BI  = FM_PLT_BMC_THERMTRIP_R_N
  Y4  GPP_D_19_MSMI_N  BI  = FM_BIOS_IMAGE_SWAP_N
  Y8  VSS_Y8  POWER  = GND
  Y11  VSS_Y11  POWER  = GND
  Y15  VSS_Y15  POWER  = GND
  Y31  VSS_Y31  POWER  = GND
  Y34  VSS_Y34  POWER  = GND
  Y37  SATA_10_PCIE3_10_GBE_0_TXP  OUT  = P3E_PCH_NVS_TX_DP<0>
  Y40  SATA_5_PCIE3_5_USB3_5_RXN  IN  = P3E_PCH_E1S_RX_DN<1>
  Y42  SATA_5_PCIE3_5_USB3_5_RXP  IN  = P3E_PCH_E1S_RX_DP<1>

U13  9SQ440NQQI8  IC  pkg QFN100_TH_0-5_8X8  page 208
  A1  \25mpg\  IN  = FM_CK440Q_DEV_25M_EN
  A2  \25m1#\  OUT  = CLK_25M_CK440_CPU1_DN
  A3  \25m1\  OUT  = CLK_25M_CK440_CPU1_DP
  A4  \25m0#\  OUT  = CLK_25M_CK440_CPU0_DN
  A5  \25m0\  OUT  = CLK_25M_CK440_CPU0_DP
  A6  PFT_OUT  OUT  = TP_CLK_CK440_PFT_OUT_DP
  A7  \pft_out#\  OUT  = TP_CLK_CK440_PFT_OUT_DN
  A8  PFT_IN  IN  = TP_CLK_PFT_IN_DP
  A9  \pft_in#\  IN  = TP_CLK_PFT_IN_DN
  A10  SCLK  IN  = SMB_HOST_CLK_3V3AUX_SCL
  A11  SMB_ADR0_TRI  IN  = CLK_CK440_SMB_ADDR0
  A12  VDDXTAL  POWER  = P3V3_AUX_CLK_GEN_VDDXTAL_CK440
  A13  XIN_CLKIN  IN  = XTAL_CLK_GEN1_25M_X1
  A14  GNDXTAL  POWER  = GND
  A15  NC_A15  TRI  = NC_CK440_A15
  A16  SS_EN_TRI  IN  = FM_CLK_CK440_SS_EN
  A17  \pwrgd||pwrdn#\  IN  = FM_PLD_CLKS_DEV_EN
  A18  \100m6#\  OUT  = NC_CLK_CK440_100M6_DN
  A19  \100m6\  OUT  = NC_CLK_CK440_100M6_DP
  A20  \100m5#\  OUT  = NC_CLK_CK440_100M5_DN
  A21  \100m5\  OUT  = NC_CLK_CK440_100M5_DP
  A22  \100m4#\  OUT  = NC_CLK_CK440_100M4_DN
  A23  \100m4\  OUT  = NC_CLK_CK440_100M4_DP
  A24  \100m3#\  OUT  = NC_CLK_CK440_100M3_DN
  A25  \100m3\  OUT  = NC_CLK_CK440_100M3_DP
  A26  \oe3#\  IN  = CK440Q_OE_3
  A27  \100m2#\  OUT  = NC_CLK_CK440_100M2_DN
  A28  \100m2\  OUT  = NC_CLK_CK440_100M2_DP
  A29  \oe2#\  IN  = CK440Q_OE_2
  A30  \oe1#\  IN  = CK440Q_OE_1
  A31  \100m1#\  OUT  = NC_CLK_CK440_100M1_DN
  A32  \100m1\  OUT  = NC_CLK_CK440_100M1_DP
  A33  \100m0#\  OUT  = CLK_100M_DB2000_DN
  A34  \100m0\  OUT  = CLK_100M_DB2000_DP
  A35  \mxck8#\  OUT  = NC_CLK_CK440_MXCK8_DN
  A36  MXCK8  OUT  = NC_CLK_CK440_MXCK8_DP
  A37  \mxck7#\  OUT  = NC_CLK_CK440_MXCK7_DN
  A38  MXCK7  OUT  = NC_CLK_CK440_MXCK7_DP
  A39  \mxck6#\  OUT  = NC_CLK_CK440_MXCK6_DN
  A40  MXCK6  OUT  = NC_CLK_CK440_MXCK6_DP
  A41  \mxck5#\  OUT  = NC_CLK_CK440_MXCK5_DN
  A42  MXCK5  OUT  = NC_CLK_CK440_MXCK5_DP
  A43  \mxck4#\  OUT  = NC_CLK_CK440_MXCK4_DN
  A44  MXCK4  OUT  = NC_CLK_CK440_MXCK4_DP
  A45  \mxck3#\  OUT  = NC_CLK_CK440_MXCK3_DN
  A46  MXCK3  OUT  = NC_CLK_CK440_MXCK3_DP
  A47  \mxck2#\  OUT  = CLK_100M_CK440_PCH_EXTCLK_R_DN
  A48  MXCK2  OUT  = CLK_100M_CK440_PCH_EXTCLK_R_DP
  A49  \mxck1#\  OUT  = NC_CLK_CK440_MXCK1_DN
  A50  MXCK1  OUT  = NC_CLK_CK440_MXCK1_DP
  A51  \mxck0#\  OUT  = NC_CLK_CK440_MXCK0_DN
  A52  MXCK0  OUT  = NC_CLK_CK440_MXCK0_DP
  A53  SBI_OUT  OUT  = TP_CK440_SBI_DATA_OUT
  A54  SBI_CLK  IN  = PD_CK440_SBI_CLK
  A55  \25m2#\  OUT  = CLK_25M_CK440_ISCLK_REF_DN
  A56  \25m2\  OUT  = CLK_25M_CK440_ISCLK_REF_DP
  B1  VDDA25M  POWER  = P3V3_AUX_CLK_GEN_VDDA25M_CK440
  B2  NC_B2  TRI  = NC_CK440_B2
  B3  NC_B3  TRI  = NC_CK440_B3
  B4  \pft_lost#\  OUT  = PU_CLK_PFT_LOST_N
  B5  NC_B5  TRI  = NC_CK440_B5
  B6  VDDPT  POWER  = P3V3_AUX_CLK_GEN_VDDPT_CK440
  B7  NC_B7  TRI  = NC_CK440_B7
  B8  SMBDATTA  BI  = SMB_HOST_CLK_3V3AUX_SDA
  B9  SMB_ADR1_TRI  IN  = CLK_CK440_SMB_ADDR1
  B10  GNDS  POWER  = GND
  B11  XOUT  OUT  = XTAL_CLK_GEN1_25M_X2
  B12  NVGND  POWER  = GND
  B13  NC_B13  TRI  = NC_CK440_B13
  B14  \oe6#\  IN  = CK440Q_OE_6
  B15  \oe5#\  IN  = CK440Q_OE_5
  B16  NC_B16  TRI  = NC_CK440_B16
  B17  VDDA100M  POWER  = P3V3_AUX_CLK_GEN_VDDA100M_CK440
  B18  NC_B18  TRI  = NC_CK440_B18
  B19  \oe4#\  IN  = CK440Q_OE_4
  B20  NC_B20  TRI  = NC_CK440_B20
  B21  VDD100M_B21  POWER  = P3V3_AUX_CLK_GEN_VDD_CK440
  B22  NC_B22  TRI  = NC_CK440_B22
  B23  VDD100M_B23  POWER  = P3V3_AUX_CLK_GEN_VDD_CK440
  B24  NC_B24  TRI  = NC_CK440_B24
  B25  NC_B25  TRI  = NC_CK440_B25
  B26  NC_B26  TRI  = NC_CK440_B26
  B27  \oe0#\  IN  = FM_CLK_GEN1_OE0_N
  B28  NC_B28  TRI  = NC_CK440_B28
  B29  VDDMXCK_B29  POWER  = P3V3_AUX_CLK_GEN_VDDMXCK_CK440
  B30  NC_B30  TRI  = NC_CK440_B30
  B31  NC_B31  TRI  = NC_CK440_B31
  B32  VDDMXCK_B32  POWER  = P3V3_AUX_CLK_GEN_VDDMXCK_CK440
  B33  NC_B33  TRI  = NC_CK440_B33
  B34  NC_B34  TRI  = NC_CK440_B34
  B35  VDDMXCK_B35  POWER  = P3V3_AUX_CLK_GEN_VDDMXCK_CK440
  B36  NC_B36  TRI  = NC_CK440_B36
  B37  NC_B37  TRI  = NC_CK440_B37
  B38  \mxck_sel_100m#\  IN  = FM_CK440_MXCK_25M_100M
  B39  NC_B39  TRI  = NC_CK440_B39
  B40  VDDMXCK_B40  POWER  = P3V3_AUX_CLK_GEN_VDDMXCK_CK440
  B41  NC_B41  TRI  = NC_CK440_B41
  B42  \shft_ld#\  IN  = PU_CK440_SHFT_LD_N
  B43  SBI_IN  IN  = PD_CK440_SBI_DATA_IN
  B44  NC_B44  TRI  = NC_CK440_B44
  C1  EPAD  POWER  = GND

U14  QS3VH257QG8  IC  pkg SMLF  page 230
  1  S  IN  = FM_SPD_REMOTE_EN
  2  I0A  IN  = I3C_SPD_DDRABCD_CPU1_R_SCL
  3  I1A  IN  = I3C_SPD_DDRABCD_CPU1_BMC_SCL
  4  YA  OUT  = I3C_SPD_DDRABCD_CPU1_LVC1_R_SCL
  5  I0B  IN  = I3C_SPD_DDRABCD_CPU1_R_SDA
  6  I1B  IN  = I3C_SPD_DDRABCD_CPU1_BMC_SDA
  7  YB  OUT  = I3C_SPD_DDRABCD_CPU1_LVC1_R_SDA
  8  GND  POWER  = GND
  9  YC  OUT  = I3C_SPD_DDREFGH_CPU1_LVC1_R_SCL
  10  I1C  IN  = I3C_SPD_DDREFGH_CPU1_BMC_SCL
  11  I0C  IN  = I3C_SPD_DDREFGH_CPU1_R_SCL
  12  YD  OUT  = I3C_SPD_DDREFGH_CPU1_LVC1_R_SDA
  13  I1D  IN  = I3C_SPD_DDREFGH_CPU1_BMC_SDA
  14  I0D  IN  = I3C_SPD_DDREFGH_CPU1_R_SDA
  15  \e*\  IN  = PD_I3C_SPD_DDR_CPU1_OE_N
  16  VCC  POWER  = P3V3_AUX

U15  QS3VH257QG8  IC  pkg SMLF  page 229
  1  S  IN  = FM_SPD_REMOTE_EN
  2  I0A  IN  = I3C_SPD_DDRABCD_CPU0_R_SCL
  3  I1A  IN  = I3C_SPD_DDRABCD_CPU0_BMC_SCL
  4  YA  OUT  = I3C_SPD_DDRABCD_CPU0_LVC1_R_SCL
  5  I0B  IN  = I3C_SPD_DDRABCD_CPU0_R_SDA
  6  I1B  IN  = I3C_SPD_DDRABCD_CPU0_BMC_SDA
  7  YB  OUT  = I3C_SPD_DDRABCD_CPU0_LVC1_R_SDA
  8  GND  POWER  = GND
  9  YC  OUT  = I3C_SPD_DDREFGH_CPU0_LVC1_R_SCL
  10  I1C  IN  = I3C_SPD_DDREFGH_CPU0_BMC_SCL
  11  I0C  IN  = I3C_SPD_DDREFGH_CPU0_R_SCL
  12  YD  OUT  = I3C_SPD_DDREFGH_CPU0_LVC1_R_SDA
  13  I1D  IN  = I3C_SPD_DDREFGH_CPU0_BMC_SDA
  14  I0D  IN  = I3C_SPD_DDREFGH_CPU0_R_SDA
  15  \e*\  IN  = PD_I3C_SPD_DDR_CPU0_OE_N
  16  VCC  POWER  = P3V3_AUX

U16  74LVC1G66GV  IC  pkg SC74AXA  page 133
  1  Y  BI  = JTAG_CPU0_MUX_GTL_TDO
  2  Z  BI  = JTAG_MUX_CPU1_GTL_TDI
  3  GND  POWER  = GND
  4  E  IN  = FM_CPU_EN_R
  5  VCC  POWER  = P3V3_AUX

U17  74CBTLV3126PW  IC  pkg TSSOP14  page 132
  1  \1oe\  IN  = PWRGD_PVNN_MAIN_CPU0
  2  \1a\  POWER  = JTAG_DBP_TMS
  3  \1b\  BI  = JTAG_DBP_CPU_QS_GTL_TMS
  4  \2oe\  OUT  = PWRGD_PVNN_MAIN_CPU0
  5  \2a\  BI  = JTAG_DBP_TDI
  6  \2b\  BI  = JTAG_QS_MUX_GTL_TDI
  7  GND  POWER  = GND
  8  \3b\  BI  = TP_74CB_B8
  9  \3a\  BI  = PD_74CB_A9
  10  \3oe\  BI  = PWRGD_PVNN_MAIN_CPU0
  11  \4b\  BI  = JTAG_MUX_QS_GTL_TDO
  12  \4a\  BI  = JTAG_DBP_TDO
  13  \4oe\  BI  = PWRGD_PVNN_MAIN_CPU0
  14  VCC  BI  = P3V3_AUX

U18  74CBTLV3126PW  IC  pkg TSSOP14  page 132
  1  \1oe\  IN  = PWRGD_PVNN_MAIN_CPU0
  2  \1a\  POWER  = JTAG_DBP_CPU_HOOK9_MBP3_GTL_N
  3  \1b\  BI  = DBP_CPU_HOOK9_MBP3_GTL_QS_N
  4  \2oe\  OUT  = PWRGD_PVNN_MAIN_CPU0
  5  \2a\  BI  = JTAG_DBP_CPU_HOOK8_MBP2_GTL_N
  6  \2b\  BI  = DBP_CPU_HOOK8_MBP2_GTL_QS_N
  7  GND  POWER  = GND
  8  \3b\  BI  = H_CPU_PRDY_QS_GTL_N
  9  \3a\  BI  = JTAG_DBP_PRDY_N
  10  \3oe\  BI  = PWRGD_PVNN_MAIN_CPU0
  11  \4b\  BI  = H_CPU_PREQ_QS_GTL_N
  12  \4a\  BI  = JTAG_DBP_PREQ_N
  13  \4oe\  BI  = PWRGD_PVNN_MAIN_CPU0
  14  VCC  BI  = P3V3_AUX

U21  NC7SB3157  NC7SB3157P6X IC  pkg SMLF  page 133
  1  B1  BI  = JTAG_MUX_CPU1_GTL_TDI
  2  GND  POWER  = GND
  3  B0  BI  = JTAG_MUX_CPU0_GTL_TDI
  4  A  BI  = JTAG_QS_MUX_GTL_TDI
  5  VCC  POWER  = P3V3_AUX
  6  S  IN  = FM_CPU0_SKTOCC_N

U22  NC7SB3157  NC7SB3157P6X IC  pkg SMLF  page 133
  1  B1  BI  = JTAG_CPU0_MUX_GTL_TDO
  2  GND  POWER  = GND
  3  B0  BI  = JTAG_CPU1_MUX_GTL_TDO
  4  A  BI  = JTAG_MUX_QS_GTL_TDO
  5  VCC  POWER  = P3V3_AUX
  6  S  IN  = FM_CPU1_SKTOCC_N

U23  74LVC1G02GW  IC  pkg SMLF  page 133
  1  B  IN  = FM_CPU1_SKTOCC_N
  2  A  IN  = FM_CPU0_SKTOCC_N
  3  GND  POWER  = GND
  4  Y  OUT  = FM_CPU_EN
  5  VCC  POWER  = P3V3_AUX

U28  PCA9617ADP  IC  pkg TSSOP8_3XB  page 235
  1  VCCA  POWER  = PVNN_TERM_CPU0
  2  SCLA  BI  = SMB_PEHPCPU0_GTL_R_SCL
  3  SDAA  BI  = SMB_PEHPCPU0_GTL_R_SDA
  4  GND  POWER  = GND
  5  EN  IN  = TP_SMB_PEHPCPU0_EN
  6  SDAB  BI  = SMB_PEHPCPU0_LVC3_SDA_R0
  7  SCLB  BI  = SMB_PEHPCPU0_LVC3_SCL_R0
  8  VCCB  POWER  = P3V3_AUX
